FILE_TYPE = CONNECTIVITY;
{Allegro Design Entry HDL 17.4-2019 S026 (4007227) 1/17/2022}
"PAGE_NUMBER" = 324;
0"NC";
1"GND\g";
2"GND\g";
3"GND\g";
4"GND\g";
5"GND\g";
6"P12V_AUX\g";
7"GND\g";
8"GND\g";
9"GND\g";
10"GND\g";
11"GND\g";
12"GND\g";
13"GND\g";
14"GND\g";
15"P12V_AUX\g";
16"P12V_E1S_0_EN_G";
17"GND\g";
18"P12V_E1S_0\g";
19"P3V3_AUX\g";
20"GND\g";
21"GND\g";
22"P3V3_E1S_0_R\g";
23"GND\g";
24"P3V3_AUX\g";
25"GND\g";
26"GND\g";
27"P12V_AUX\g";
28"GND\g";
29"P3V3_AUX\g";
30"P12V_E1S_EN_0_R";
31"E1S_0_P12V_EN";
32"P12V_E1S_UV_0_R";
33"P12V_E1S_UV_0";
34"P12V_E1S_OV_0";
35"P12V_E1S_VCC_0";
36"P12V_E1S_REG_0";
37"P12V_E1S_FAULT_0";
38"P12V_E1S_PWRGD_0";
39"P12V_E1S_GATE_0";
40"P12V_E1S_SENSE_0";
41"P12V_E1S_0_ISENSE_MAM_MAM";
42"HP_LVC3_E1S_0_HSC_PWRGD";
43"P12V_E1S_0_ISENSE_MAM_TIC";
44"P3V3_E1S_EN_0_R";
45"P3V3_E1S_0_EN_G";
46"P3V3_E1S_UV_0_R";
47"P3V3_E1S_UV_0";
48"P3V3_E1S_VCC_0";
49"P3V3_E1S_OV_0";
50"P3V3_E1S_REG_0";
51"P3V3_E1S_GATE_0";
52"P3V3_E1S_CB_0";
53"P3V3_E1S_PWRGD_0";
54"P3V3_E1S_FAULT_0";
55"P3V3_E1S_PWRGD_0_R";
56"P3V3_E1S_SENSE_0";
57"E1S_0_P3V3_EN";
58"P12V_E1S_CB_0";
%"GND"
"1","(-3000,-700)","0","pure_quanta_power","I10";
;
CDS_LIB"pure_quanta_power"
SIZE"1B"
HDL_POWER"GND";
"A<SIZE-1..0>\NAC"1;
%"Q_RES"
"2","(-3000,-475)","0","pure_quanta","I11";
;
LOCATION"R4073"
$SEC"1"
CDS_SEC"1"
ROOM"E1S_P12V_MAM_TIC_BOM1"
TOLERANCE"5%"
VALUE"4.7K"
PACK_TYPE"0402LF"
WATTAGE"1/16W"
MATERIAL"CHIP"
CDS_LIB"pure_quanta"
PART_NUMBER"CS24702JB10";
"A"
$PN"1"30;
"B"
$PN"2"1;
%"MOSFET_NCH_DUAL"
"1","(-2550,-100)","0","pure_quanta","I12";
;
LOCATION"Q127"
$SEC"1"
CDS_SEC"1"
PART_TYPE"SMLF"
MATERIAL"IC"
VALUE"PJT138K"
ROOM"E1S_P12V_MAM_TIC_BOM1"
NEEDS_NO_SIZE"TRUE"
CDS_LMAN_SYM_OUTLINE"-150,150,150,-150"
CDS_LIB"pure_quanta"
PART_NUMBER"BAM138K0003";
"D1"
$PN"6"16;
"G1"
$PN"2"30;
"S1"
$PN"1"2;
%"GND"
"1","(-2500,-450)","0","pure_quanta_power","I13";
;
CDS_LIB"pure_quanta_power"
SIZE"1B"
HDL_POWER"GND";
"A<SIZE-1..0>\NAC"2;
%"GND"
"1","(-2050,-2575)","0","pure_quanta_power","I14";
;
CDS_LIB"pure_quanta_power"
SIZE"1B"
HDL_POWER"GND";
"A<SIZE-1..0>\NAC"3;
%"GND"
"1","(-125,-2825)","0","pure_quanta_power","I15";
;
SIZE"1B"
CDS_LIB"pure_quanta_power"
HDL_POWER"GND";
"A<SIZE-1..0>\NAC"4;
%"Q_RES"
"2","(-125,-2575)","0","pure_quanta","I16";
;
LOCATION"PR3965"
$SEC"1"
CDS_SEC"1"
WATTAGE"1/16W"
ROOM"E1S_P3V3_BOM1"
PACK_TYPE"0402LF"
VALUE"15K"
TOLERANCE"1%"
MATERIAL"CHIP"
CDS_LIB"pure_quanta"
PART_NUMBER"CS31502FB05";
"A"
$PN"1"49;
"B"
$PN"2"4;
%"Q_RES"
"2","(-125,-2300)","0","pure_quanta","I17";
;
LOCATION"PR3964"
$SEC"1"
CDS_SEC"1"
WATTAGE"1/16W"
ROOM"E1S_P3V3_BOM1"
TOLERANCE"1%"
VALUE"7.15K"
PACK_TYPE"0402LF"
MATERIAL"CHIP"
CDS_LIB"pure_quanta"
PART_NUMBER"CS27152FB03";
"A"
$PN"1"47;
"B"
$PN"2"49;
%"Q_RES"
"1","(-600,-1950)","0","pure_quanta","I18";
;
LOCATION"R3959"
$SEC"1"
CDS_SEC"1"
WATTAGE"1/16W"
TOLERANCE"5%"
VALUE"0"
PACK_TYPE"0402LF"
MATERIAL"CHIP"
ROOM"E1S_P3V3_BOM1"
CDS_LIB"pure_quanta"
PART_NUMBER"CS00002JB13";
"B"
$PN"2"47;
"A"
$PN"1"46;
%"GND"
"1","(-475,-1600)","0","pure_quanta_power","I19";
;
CDS_LIB"pure_quanta_power"
SIZE"1B"
HDL_POWER"GND";
"A<SIZE-1..0>\NAC"5;
%"Q_RES"
"1","(-3650,-2650)","0","pure_quanta","I2";
;
LOCATION"R4063"
$SEC"1"
CDS_SEC"1"
WATTAGE"1/16W"
MATERIAL"CHIP"
TOLERANCE"5%"
PACK_TYPE"0402LF"
VALUE"0"
ROOM"E1S_P3V3_BOM1"
CDS_LIB"pure_quanta"
PART_NUMBER"CS00002JB13";
"B"
$PN"2"44;
"A"
$PN"1"57;
%"Q_CAP"
"1","(-475,-1325)","0","pure_quanta","I20";
;
LOCATION"PC2208"
$SEC"1"
CDS_SEC"1"
PACK_TYPE"C0402"
VALUE"1UF"
VOLTAGE"25V"
MATERIAL"X6S"
CDS_LIB"pure_quanta"
TOLERANCE"10%"
PART_NUMBER"CH5104KEB02";
"B"
$PN"2"5;
"A"
$PN"1"29;
%"Q_RES"
"2","(-125,-1575)","0","pure_quanta","I21";
;
LOCATION"PR3963"
$SEC"1"
CDS_SEC"1"
ROOM"E1S_P3V3_BOM1"
PACK_TYPE"0402LF"
MATERIAL"CHIP"
WATTAGE"1/16W"
VALUE"25.5K"
TOLERANCE"1%"
CDS_LIB"pure_quanta"
PART_NUMBER"CS32552FB06";
"A"
$PN"1"29;
"B"
$PN"2"47;
%"UNIVERSAL_POWER"
"1","(-475,-975)","0","pure_quanta_power","I22";
;
HDL_POWER"P3V3_AUX"
CDS_LIB"pure_quanta_power";
"A"29;
%"Q_RES"
"1","(-3375,-150)","0","pure_quanta","I24";
;
LOCATION"R4064"
$SEC"1"
CDS_SEC"1"
TOLERANCE"5%"
MATERIAL"CHIP"
VALUE"0"
WATTAGE"1/16W"
PACK_TYPE"0402LF"
ROOM"E1S_P12V_MAM_TIC_BOM1"
CDS_LIB"pure_quanta"
PART_NUMBER"CS00002JB13";
"B"
$PN"2"30;
"A"
$PN"1"31;
%"Q_RES"
"2","(-2500,500)","0","pure_quanta","I25";
;
LOCATION"R4074"
$SEC"1"
CDS_SEC"1"
VALUE"10K"
TOLERANCE"1%"
WATTAGE"1/16W"
PACK_TYPE"0402LF"
MATERIAL"CHIP"
ROOM"E1S_P12V_MAM_TIC_BOM1"
CDS_LIB"pure_quanta"
PART_NUMBER"CS31002FB08";
"A"
$PN"1"6;
"B"
$PN"2"16;
%"UNIVERSAL_POWER"
"1","(-2500,750)","0","pure_quanta_power","I26";
;
HDL_POWER"P12V_AUX"
CDS_LIB"pure_quanta_power";
"A"6;
%"MOSFET_NCH_DUAL"
"2","(-1850,275)","0","pure_quanta","I27";
;
LOCATION"Q127"
$SEC"2"
CDS_SEC"2"
ROOM"E1S_P12V_MAM_TIC_BOM1"
VALUE"PJT138K"
PART_TYPE"SMLF"
MATERIAL"IC"
NEEDS_NO_SIZE"TRUE"
CDS_LMAN_SYM_OUTLINE"-150,150,150,-150"
CDS_LIB"pure_quanta"
PART_NUMBER"BAM138K0003";
"S2"
$PN"4"7;
"G2"
$PN"5"16;
"D2"
$PN"3"32;
%"GND"
"1","(-1800,-75)","0","pure_quanta_power","I28";
;
CDS_LIB"pure_quanta_power"
SIZE"1B"
HDL_POWER"GND";
"A<SIZE-1..0>\NAC"7;
%"Q_RES"
"1","(-725,750)","0","pure_quanta","I29";
;
LOCATION"R3958"
$SEC"1"
CDS_SEC"1"
MATERIAL"CHIP"
TOLERANCE"5%"
PACK_TYPE"0402LF"
WATTAGE"1/16W"
VALUE"0"
ROOM"E1S_P12V_MAM_TIC_BOM1"
CDS_LIB"pure_quanta"
PART_NUMBER"CS00002JB13";
"B"
$PN"2"33;
"A"
$PN"1"32;
%"GND"
"1","(-3300,-3200)","0","pure_quanta_power","I3";
;
SIZE"1B"
CDS_LIB"pure_quanta_power"
HDL_POWER"GND";
"A<SIZE-1..0>\NAC"8;
%"GND"
"1","(-125,-125)","0","pure_quanta_power","I30";
;
CDS_LIB"pure_quanta_power"
SIZE"1B"
HDL_POWER"GND";
"A<SIZE-1..0>\NAC"9;
%"Q_RES"
"2","(-125,125)","0","pure_quanta","I31";
;
LOCATION"PR3962"
$SEC"1"
CDS_SEC"1"
ROOM"E1S_P12V_MAM_TIC_BOM1"
VALUE"15K"
MATERIAL"CHIP"
WATTAGE"1/16W"
PACK_TYPE"0402LF"
TOLERANCE"1%"
CDS_LIB"pure_quanta"
PART_NUMBER"CS31502FB05";
"A"
$PN"1"34;
"B"
$PN"2"9;
%"Q_RES"
"2","(-125,400)","0","pure_quanta","I32";
;
LOCATION"PR3961"
$SEC"1"
CDS_SEC"1"
VALUE"6.8K"
TOLERANCE"1%"
WATTAGE"1/16W"
MATERIAL"CHIP"
PACK_TYPE"0402LF"
ROOM"E1S_P12V_MAM_TIC_BOM1"
CDS_LIB"pure_quanta"
PART_NUMBER"CS26802FB02";
"A"
$PN"1"33;
"B"
$PN"2"34;
%"DIODE_TVS"
"1","(-900,1375)","1","pure_quanta","I33";
;
LOCATION"PD114"
$SEC"1"
CDS_SEC"1"
VALUE"SMF14A"
MATERIAL"IC"
CDS_LIB"pure_quanta"
CDS_LMAN_SYM_OUTLINE"-100,50,100,-50"
PIN_NAMES_ROTATE"TRUE"
PART_TYPE"SMLF"
PART_NUMBER"BCSMF14AZ01";
"C"
$PN"C"
Pin_Length"Short"27;
"A"
$PN"A"28;
%"GND"
"1","(-700,1000)","0","pure_quanta_power","I34";
;
SIZE"1B"
CDS_LIB"pure_quanta_power"
HDL_POWER"GND";
"A<SIZE-1..0>\NAC"28;
%"UNIVERSAL_POWER"
"1","(-700,1725)","0","pure_quanta_power","I35";
;
HDL_POWER"P12V_AUX"
CDS_LIB"pure_quanta_power";
"A"27;
%"Q_CAP"
"1","(-475,1375)","0","pure_quanta","I36";
;
LOCATION"PC2207"
$SEC"1"
CDS_SEC"1"
PACK_TYPE"C0402"
VOLTAGE"25V"
MATERIAL"X6S"
VALUE"1UF"
CDS_LIB"pure_quanta"
TOLERANCE"10%"
PART_NUMBER"CH5104KEB02";
"B"
$PN"2"28;
"A"
$PN"1"27;
%"Q_RES"
"2","(-125,1075)","0","pure_quanta","I37";
;
LOCATION"PR3960"
$SEC"1"
CDS_SEC"1"
MATERIAL"CHIP"
PACK_TYPE"0402LF"
TOLERANCE"1%"
WATTAGE"1/16W"
VALUE"160K"
ROOM"E1S_P12V_MAM_TIC_BOM1"
CDS_LIB"pure_quanta"
PART_NUMBER"CS41602FB05";
"A"
$PN"1"27;
"B"
$PN"2"33;
%"GND"
"1","(725,-2850)","0","pure_quanta_power","I38";
;
CDS_LIB"pure_quanta_power"
SIZE"1B"
HDL_POWER"GND";
"A<SIZE-1..0>\NAC"26;
%"Q_RES"
"2","(725,-2550)","0","pure_quanta","I39";
;
LOCATION"PR3969"
$SEC"1"
CDS_SEC"1"
ROOM"E1S_P3V3_BOM1"
MATERIAL"CHIP"
WATTAGE"1/16W"
VALUE"2.49K"
TOLERANCE"1%"
PACK_TYPE"0402LF"
CDS_LIB"pure_quanta"
PART_NUMBER"CS22492FB05";
"A"
$PN"1"52;
"B"
$PN"2"26;
%"Q_RES"
"2","(-3300,-2975)","0","pure_quanta","I4";
;
LOCATION"R6049"
$SEC"1"
CDS_SEC"1"
TOLERANCE"5%"
PACK_TYPE"0402LF"
MATERIAL"CHIP"
VALUE"4.7K"
WATTAGE"1/16W"
ROOM"E1S_P3V3_BOM1"
CDS_LIB"pure_quanta"
PART_NUMBER"CS24702JB10";
"A"
$PN"1"44;
"B"
$PN"2"8;
%"GND"
"1","(200,-2125)","0","pure_quanta_power","I40";
;
CDS_LIB"pure_quanta_power"
SIZE"1B"
HDL_POWER"GND";
"A<SIZE-1..0>\NAC"10;
%"Q_CAP"
"1","(200,-1750)","0","pure_quanta","I41";
;
LOCATION"PC2210"
$SEC"1"
CDS_SEC"1"
ROOM"E1S_P3V3_BOM1"
PACK_TYPE"C0402"
VOLTAGE"25V"
MATERIAL"X6S"
VALUE"1UF"
CDS_LIB"pure_quanta"
TOLERANCE"10%"
PART_NUMBER"CH5104KEB02";
"B"
$PN"2"10;
"A"
$PN"1"48;
%"Q_CAP"
"1","(425,-2050)","1","pure_quanta","I42";
;
LOCATION"PC2212"
$SEC"1"
CDS_SEC"1"
PACK_TYPE"C0402"
VALUE"1UF"
VOLTAGE"25V"
ROOM"E1S_P3V3_BOM1"
CDS_LIB"pure_quanta"
MATERIAL"X6S"
TOLERANCE"10%"
PART_NUMBER"CH5104KEB02";
"B"
$PN"2"50;
"A"
$PN"1"10;
%"Q_RES"
"2","(200,-1325)","0","pure_quanta","I43";
;
LOCATION"PR3967"
$SEC"1"
CDS_SEC"1"
MATERIAL"CHIP"
PACK_TYPE"0402LF"
ROOM"E1S_P3V3_BOM1"
TOLERANCE"1%"
VALUE"10"
WATTAGE"1/16W"
CDS_LIB"pure_quanta"
PART_NUMBER"CS01002FB07";
"A"
$PN"1"29;
"B"
$PN"2"48;
%"GND"
"1","(2200,-2725)","0","pure_quanta_power","I44";
;
SIZE"1B"
CDS_LIB"pure_quanta_power"
HDL_POWER"GND";
"A<SIZE-1..0>\NAC"25;
%"Q_RES"
"2","(2325,-2400)","0","pure_quanta","I45";
;
LOCATION"PR3971"
$SEC"1"
CDS_SEC"1"
ROOM"E1S_P3V3_BOM1"
MATERIAL"CHIP"
TOLERANCE"1%"
PACK_TYPE"0402LF"
VALUE"9.76K"
WATTAGE"1/16W"
CDS_LIB"pure_quanta"
PART_NUMBER"CS29762FB05";
"A"
$PN"1"56;
"B"
$PN"2"25;
%"Q_CAP"
"1","(2275,-1725)","0","pure_quanta","I46";
;
LOCATION"PC2213"
$SEC"1"
CDS_SEC"1"
VALUE"0.01UF"
ROOM"E1S_P3V3_BOM1"
PACK_TYPE"C0402"
VOLTAGE"50V"
MATERIAL"EMPTY"
CDS_LIB"pure_quanta"
TOLERANCE"10%"
PART_NUMBER"CH31006KB18";
"B"
$PN"2"51;
"A"
$PN"1"22;
%"Q_RES"
"2","(2550,-1725)","0","pure_quanta","I47";
;
LOCATION"PR4527"
$SEC"1"
CDS_SEC"1"
ROOM"E1S_P3V3_BOM1"
TOLERANCE"1%"
WATTAGE"1/16W"
PACK_TYPE"0402LF"
VALUE"10M"
MATERIAL"CHIP"
CDS_LIB"pure_quanta"
PART_NUMBER"CS61002FB02";
"A"
$PN"1"22;
"B"
$PN"2"51;
%"Q_RES"
"1","(2975,-2050)","0","pure_quanta","I48";
;
LOCATION"R3973"
$SEC"1"
CDS_SEC"1"
ROOM"E1S_P3V3_BOM1"
VALUE"0"
TOLERANCE"5%"
MATERIAL"CHIP"
WATTAGE"1/16W"
PACK_TYPE"0402LF"
CDS_LIB"pure_quanta"
PART_NUMBER"CS00002JB13";
"B"
$PN"2"55;
"A"
$PN"1"53;
%"Q_CAP"
"1","(3025,-1950)","1","pure_quanta","I49";
;
LOCATION"PC2216"
$SEC"1"
CDS_SEC"1"
ROOM"E1S_P3V3_BOM1"
VALUE"6800PF"
PACK_TYPE"C0402"
VOLTAGE"50V"
TOLERANCE"10%"
MATERIAL"X7R"
CDS_LIB"pure_quanta"
PART_NUMBER"CH2686K1B01";
"B"
$PN"2"12;
"A"
$PN"1"51;
%"GND"
"1","(-2725,-2950)","0","pure_quanta_power","I5";
;
SIZE"1B"
CDS_LIB"pure_quanta_power"
HDL_POWER"GND";
"A<SIZE-1..0>\NAC"11;
%"SCHOTTKY_AC"
"1","(2700,-1100)","1","pure_quanta","I50";
;
LOCATION"PD113"
$SEC"1"
CDS_SEC"1"
MATERIAL"IC"
VALUE"B340A-13-F"
NEEDS_NO_SIZE"TRUE"
CDS_LIB"pure_quanta"
CDS_LMAN_SYM_OUTLINE"-75,50,75,-50"
PART_TYPE"SMLF"
PART_NUMBER"BC000340Z30";
"C"
$PN"C"22;
"A"
$PN"A"23;
%"GND"
"1","(3150,-2000)","0","pure_quanta_power","I51";
;
SIZE"1B"
CDS_LIB"pure_quanta_power"
HDL_POWER"GND";
"A<SIZE-1..0>\NAC"12;
%"Q_RES"
"2","(3325,-1750)","0","pure_quanta","I52";
;
LOCATION"R3977"
$SEC"1"
CDS_SEC"1"
MATERIAL"CHIP"
WATTAGE"1/16W"
TOLERANCE"1%"
VALUE"100K"
ROOM"E1S_P3V3_BOM1"
PACK_TYPE"0402LF"
CDS_LIB"pure_quanta"
PART_NUMBER"CS41002FB09";
"A"
$PN"1"24;
"B"
$PN"2"54;
%"VCCAUX15"
"1","(3525,-1425)","0","pure_quanta_power","I53";
;
HDL_POWER"P3V3_AUX"
CDS_LIB"pure_quanta_power";
"A"24;
%"Q_RES"
"2","(3725,-1750)","0","pure_quanta","I54";
;
LOCATION"R3979"
$SEC"1"
CDS_SEC"1"
ROOM"E1S_P3V3_BOM1"
WATTAGE"1/16W"
MATERIAL"CHIP"
VALUE"100K"
PACK_TYPE"0402LF"
TOLERANCE"1%"
CDS_LIB"pure_quanta"
PART_NUMBER"CS41002FB09";
"A"
$PN"1"24;
"B"
$PN"2"55;
%"GND"
"1","(3775,-1425)","0","pure_quanta_power","I56";
;
SIZE"1B"
CDS_LIB"pure_quanta_power"
HDL_POWER"GND";
"A<SIZE-1..0>\NAC"23;
%"Q_CAP"
"1","(3200,-1125)","0","pure_quanta","I57";
;
LOCATION"PC2218"
$SEC"1"
CDS_SEC"1"
PACK_TYPE"0402"
MATERIAL"X7R"
VOLTAGE"25V"
VALUE"0.1UF"
CDS_LIB"pure_quanta"
TOLERANCE"10%"
PART_NUMBER"CH4104K1B00";
"B"
$PN"2"23;
"A"
$PN"1"22;
%"Q_CAP"
"1","(3775,-1125)","0","pure_quanta","I58";
;
LOCATION"PC2220"
$SEC"1"
CDS_SEC"1"
PACK_TYPE"C0805"
MATERIAL"X6S"
VALUE"10UF"
VOLTAGE"16V"
TOLERANCE"10%"
CDS_LIB"pure_quanta"
PART_NUMBER"CH6103KEA01";
"B"
$PN"2"23;
"A"
$PN"1"22;
%"UNIVERSAL_POWER"
"1","(3775,-825)","2","pure_quanta_power","I59";
;
HDL_POWER"P3V3_E1S_0_R"
CDS_LIB"pure_quanta_power";
"A"22;
%"MOSFET_NCH_DUAL"
"1","(-2775,-2600)","0","pure_quanta","I6";
;
LOCATION"Q126"
$SEC"1"
CDS_SEC"1"
MATERIAL"IC"
VALUE"PJT138K"
PART_TYPE"SMLF"
ROOM"E1S_P3V3_BOM1"
CDS_LIB"pure_quanta"
CDS_LMAN_SYM_OUTLINE"-150,150,150,-150"
NEEDS_NO_SIZE"TRUE"
PART_NUMBER"BAM138K0003";
"D1"
$PN"6"45;
"G1"
$PN"2"44;
"S1"
$PN"1"11;
%"GND"
"1","(200,575)","0","pure_quanta_power","I60";
;
CDS_LIB"pure_quanta_power"
SIZE"1B"
HDL_POWER"GND";
"A<SIZE-1..0>\NAC"13;
%"Q_CAP"
"1","(425,650)","1","pure_quanta","I61";
;
LOCATION"PC2211"
$SEC"1"
CDS_SEC"1"
PACK_TYPE"C0402"
ROOM"E1S_P12V_MAM_TIC_BOM1"
VALUE"1UF"
VOLTAGE"25V"
TOLERANCE"10%"
MATERIAL"X6S"
CDS_LIB"pure_quanta"
PART_NUMBER"CH5104KEB02";
"B"
$PN"2"36;
"A"
$PN"1"13;
%"GND"
"1","(725,-150)","0","pure_quanta_power","I62";
;
CDS_LIB"pure_quanta_power"
SIZE"1B"
HDL_POWER"GND";
"A<SIZE-1..0>\NAC"21;
%"Q_RES"
"2","(725,150)","0","pure_quanta","I63";
;
LOCATION"PR3968"
$SEC"1"
CDS_SEC"1"
ROOM"E1S_P12V_MAM_TIC_BOM1"
PACK_TYPE"0402LF"
MATERIAL"CHIP"
WATTAGE"1/16W"
TOLERANCE"1%"
VALUE"9.31K"
CDS_LIB"pure_quanta"
PART_NUMBER"CS29312FB02";
"A"
$PN"1"58;
"B"
$PN"2"21;
%"Q_CAP"
"1","(200,950)","0","pure_quanta","I64";
;
LOCATION"PC2209"
$SEC"1"
CDS_SEC"1"
PACK_TYPE"C0402"
VOLTAGE"25V"
MATERIAL"X6S"
VALUE"1UF"
ROOM"E1S_P12V_MAM_TIC_BOM1"
CDS_LIB"pure_quanta"
TOLERANCE"10%"
PART_NUMBER"CH5104KEB02";
"B"
$PN"2"13;
"A"
$PN"1"35;
%"Q_RES"
"2","(200,1375)","0","pure_quanta","I65";
;
LOCATION"PR3966"
$SEC"1"
CDS_SEC"1"
PACK_TYPE"0402LF"
WATTAGE"1/16W"
ROOM"E1S_P12V_MAM_TIC_BOM1"
TOLERANCE"1%"
VALUE"10"
MATERIAL"CHIP"
CDS_LIB"pure_quanta"
PART_NUMBER"CS01002FB07";
"A"
$PN"1"27;
"B"
$PN"2"35;
%"MAX15090BEWIT"
"1","(1475,650)","0","pure_quanta","I66";
;
LOCATION"PU294"
$SEC"1"
CDS_SEC"1"
ROOM"E1S_P12V_MAM_TIC_BOM1"
MATERIAL"IC"
PART_TYPE"SMLF"
VALUE"MAX15090BEWI+T"
CDS_LMAN_SYM_OUTLINE"-250,550,250,-550"
CDS_LIB"pure_quanta"
PIN_NAMES_ROTATE"TRUE"
PART_NUMBER"AL015080B00";
"PG"
$PN"D7"38;
"FAULT# \B"
$PN"C7"37;
"GND_C2"
$PN"C2"20;
"GND_C1"
$PN"C1"20;
"GND_B2"
$PN"B2"20;
"CDLY"
$PN"A7"20;
"GATE"
$PN"A6"39;
"OUT_D6"
$PN"D6"18;
"OUT_D4"
$PN"D4"18;
"OUT_C6"
$PN"C6"18;
"OUT_C4"
$PN"C4"18;
"OUT_B6"
$PN"B6"18;
"OUT_B4"
$PN"B4"18;
"OUT_A4"
$PN"A4"18;
"ISENSE"
$PN"A1"40;
"OV"
$PN"D3"34;
"UV"
$PN"D2"33;
"REG"
$PN"D1"36;
"EN# \B"
$PN"B7"21;
"CB"
$PN"B1"58;
"IN_D5"
$PN"D5"27;
"IN_C5"
$PN"C5"27;
"IN_C3"
$PN"C3"27;
"IN_B5"
$PN"B5"27;
"IN_B3"
$PN"B3"27;
"IN_A5"
$PN"A5"27;
"IN_A3"
$PN"A3"27;
"VCC"
$PN"A2"35;
%"GND"
"1","(2200,-25)","0","pure_quanta_power","I67";
;
SIZE"1B"
CDS_LIB"pure_quanta_power"
HDL_POWER"GND";
"A<SIZE-1..0>\NAC"20;
%"Q_RES"
"2","(2325,275)","0","pure_quanta","I68";
;
LOCATION"PR3970"
$SEC"1"
CDS_SEC"1"
MATERIAL"CHIP"
PACK_TYPE"0402LF"
ROOM"E1S_P12V_MAM_TIC_BOM1"
WATTAGE"1/16W"
VALUE"2.67K"
TOLERANCE"1%"
CDS_LIB"pure_quanta"
PART_NUMBER"CS22672FB03";
"A"
$PN"1"40;
"B"
$PN"2"20;
%"Q_CAP"
"1","(2825,750)","1","pure_quanta","I69";
;
LOCATION"PC2215"
$SEC"1"
CDS_SEC"1"
PACK_TYPE"C0402"
ROOM"E1S_P12V_MAM_TIC_BOM1"
VOLTAGE"50V"
VALUE"3900PF"
TOLERANCE"10%"
MATERIAL"X7R"
CDS_LIB"pure_quanta"
PART_NUMBER"CH23906KB14";
"B"
$PN"2"14;
"A"
$PN"1"39;
%"MOSFET_NCH_DUAL"
"2","(-2100,-2275)","0","pure_quanta","I7";
;
LOCATION"Q126"
$SEC"2"
CDS_SEC"2"
MATERIAL"IC"
ROOM"E1S_P3V3_BOM1"
VALUE"PJT138K"
PART_TYPE"SMLF"
CDS_LIB"pure_quanta"
CDS_LMAN_SYM_OUTLINE"-150,150,150,-150"
NEEDS_NO_SIZE"TRUE"
PART_NUMBER"BAM138K0003";
"S2"
$PN"4"3;
"G2"
$PN"5"45;
"D2"
$PN"3"46;
%"Q_RES"
"1","(3100,450)","0","pure_quanta","I70";
;
LOCATION"R3974"
$SEC"1"
CDS_SEC"1"
WATTAGE"1/16W"
PACK_TYPE"0402LF"
TOLERANCE"5%"
VALUE"0"
MATERIAL"EMPTY"
CDS_LIB"pure_quanta"
PART_NUMBER"CS00002JB13";
"B"
$PN"2"41;
"A"
$PN"1"40;
%"Q_RES"
"1","(2950,650)","0","pure_quanta","I71";
;
LOCATION"R3972"
$SEC"1"
CDS_SEC"1"
TOLERANCE"5%"
VALUE"0"
ROOM"E1S_P12V_MAM_TIC_BOM1"
WATTAGE"1/16W"
PACK_TYPE"0402LF"
MATERIAL"CHIP"
CDS_LIB"pure_quanta"
PART_NUMBER"CS00002JB13";
"B"
$PN"2"42;
"A"
$PN"1"38;
%"Q_CAP"
"1","(2275,975)","0","pure_quanta","I72";
;
LOCATION"PC2214"
$SEC"1"
CDS_SEC"1"
MATERIAL"EMPTY"
PACK_TYPE"C0402"
ROOM"E1S_P12V_MAM_TIC_BOM1"
VOLTAGE"50V"
VALUE"0.01UF"
TOLERANCE"10%"
CDS_LIB"pure_quanta"
PART_NUMBER"CH31006KB18";
"B"
$PN"2"39;
"A"
$PN"1"18;
%"Q_RES"
"2","(2600,1000)","0","pure_quanta","I73";
;
LOCATION"PR4528"
$SEC"1"
CDS_SEC"1"
ROOM"E1S_P12V_MAM_TIC_BOM1"
PACK_TYPE"0402LF"
MATERIAL"CHIP"
TOLERANCE"1%"
WATTAGE"1/16W"
VALUE"10M"
CDS_LIB"pure_quanta"
PART_NUMBER"CS61002FB02";
"A"
$PN"1"18;
"B"
$PN"2"39;
%"SCHOTTKY_AC"
"1","(2700,1600)","1","pure_quanta","I74";
;
LOCATION"PD112"
$SEC"1"
CDS_SEC"1"
MATERIAL"IC"
VALUE"B340A-13-F"
NEEDS_NO_SIZE"TRUE"
CDS_LMAN_SYM_OUTLINE"-75,50,75,-50"
CDS_LIB"pure_quanta"
PART_TYPE"SMLF"
PART_NUMBER"BC000340Z30";
"C"
$PN"C"18;
"A"
$PN"A"17;
%"GND"
"1","(3075,700)","0","pure_quanta_power","I75";
;
CDS_LIB"pure_quanta_power"
SIZE"1B"
HDL_POWER"GND";
"A<SIZE-1..0>\NAC"14;
%"Q_RES"
"2","(3300,900)","0","pure_quanta","I76";
;
LOCATION"R3976"
$SEC"1"
CDS_SEC"1"
WATTAGE"1/16W"
TOLERANCE"1%"
ROOM"E1S_P12V_MAM_TIC_BOM1"
MATERIAL"CHIP"
PACK_TYPE"0402LF"
VALUE"100K"
CDS_LIB"pure_quanta"
PART_NUMBER"CS41002FB09";
"A"
$PN"1"19;
"B"
$PN"2"37;
%"VCCAUX15"
"1","(3500,1250)","0","pure_quanta_power","I77";
;
HDL_POWER"P3V3_AUX"
CDS_LIB"pure_quanta_power";
"A"19;
%"Q_CAP"
"1","(3175,1575)","0","pure_quanta","I78";
;
LOCATION"PC2217"
$SEC"1"
CDS_SEC"1"
VOLTAGE"25V"
VALUE"0.1UF"
MATERIAL"X7R"
PACK_TYPE"0402"
CDS_LIB"pure_quanta"
TOLERANCE"10%"
PART_NUMBER"CH4104K1B00";
"B"
$PN"2"17;
"A"
$PN"1"18;
%"Q_CAP"
"1","(3600,1575)","0","pure_quanta","I79";
;
LOCATION"PC2219"
$SEC"1"
CDS_SEC"1"
PACK_TYPE"C0805"
MATERIAL"X6S"
VOLTAGE"16V"
VALUE"10UF"
TOLERANCE"10%"
CDS_LIB"pure_quanta"
PART_NUMBER"CH6103KEA01";
"B"
$PN"2"17;
"A"
$PN"1"18;
%"Q_RES"
"2","(-2725,-2000)","0","pure_quanta","I8";
;
LOCATION"R4072"
$SEC"1"
CDS_SEC"1"
VALUE"10K"
WATTAGE"1/16W"
TOLERANCE"1%"
ROOM"E1S_P3V3_BOM1"
MATERIAL"CHIP"
PACK_TYPE"0402LF"
CDS_LIB"pure_quanta"
PART_NUMBER"CS31002FB08";
"A"
$PN"1"15;
"B"
$PN"2"45;
%"Q_CAP"
"1","(4000,1575)","0","pure_quanta","I80";
;
LOCATION"PC2280"
$SEC"1"
CDS_SEC"1"
PACK_TYPE"C0805"
VALUE"10UF"
VOLTAGE"16V"
MATERIAL"X6S"
CDS_LIB"pure_quanta"
TOLERANCE"10%"
PART_NUMBER"CH6103KEA01";
"B"
$PN"2"17;
"A"
$PN"1"18;
%"UNIVERSAL_POWER"
"1","(4000,1875)","2","pure_quanta_power","I81";
;
HDL_POWER"P12V_E1S_0"
CDS_LIB"pure_quanta_power";
"A"18;
%"GND"
"1","(4000,1275)","0","pure_quanta_power","I85";
;
SIZE"1B"
CDS_LIB"pure_quanta_power"
HDL_POWER"GND";
"A<SIZE-1..0>\NAC"17;
%"Q_RES"
"2","(3725,900)","0","pure_quanta","I86";
;
LOCATION"R3978"
$SEC"1"
CDS_SEC"1"
WATTAGE"1/16W"
ROOM"E1S_P12V_MAM_TIC_BOM1"
PACK_TYPE"0402LF"
MATERIAL"CHIP"
TOLERANCE"1%"
VALUE"100K"
CDS_LIB"pure_quanta"
PART_NUMBER"CS41002FB09";
"A"
$PN"1"19;
"B"
$PN"2"42;
%"Q_RES"
"1","(3100,225)","0","pure_quanta","I87";
;
LOCATION"R3975"
$SEC"1"
CDS_SEC"1"
MATERIAL"CHIP"
ROOM"E1S_P12V_MAM_TIC_BOM1"
WATTAGE"1/16W"
TOLERANCE"5%"
VALUE"0"
PACK_TYPE"0402LF"
CDS_LIB"pure_quanta"
PART_NUMBER"CS00002JB13";
"B"
$PN"2"43;
"A"
$PN"1"40;
%"MAX15090BEWIT"
"1","(1475,-2050)","0","pure_quanta","I88";
;
LOCATION"PU295"
$SEC"1"
CDS_SEC"1"
VALUE"MAX15090BEWI+T"
PART_TYPE"SMLF"
ROOM"E1S_P3V3_BOM1"
MATERIAL"IC"
CDS_LMAN_SYM_OUTLINE"-250,550,250,-550"
CDS_LIB"pure_quanta"
PIN_NAMES_ROTATE"TRUE"
PART_NUMBER"AL015080B00";
"PG"
$PN"D7"53;
"FAULT# \B"
$PN"C7"54;
"GND_C2"
$PN"C2"25;
"GND_C1"
$PN"C1"25;
"GND_B2"
$PN"B2"25;
"CDLY"
$PN"A7"25;
"GATE"
$PN"A6"51;
"OUT_D6"
$PN"D6"22;
"OUT_D4"
$PN"D4"22;
"OUT_C6"
$PN"C6"22;
"OUT_C4"
$PN"C4"22;
"OUT_B6"
$PN"B6"22;
"OUT_B4"
$PN"B4"22;
"OUT_A4"
$PN"A4"22;
"ISENSE"
$PN"A1"56;
"OV"
$PN"D3"49;
"UV"
$PN"D2"47;
"REG"
$PN"D1"50;
"EN# \B"
$PN"B7"26;
"CB"
$PN"B1"52;
"IN_D5"
$PN"D5"29;
"IN_C5"
$PN"C5"29;
"IN_C3"
$PN"C3"29;
"IN_B5"
$PN"B5"29;
"IN_B3"
$PN"B3"29;
"IN_A5"
$PN"A5"29;
"IN_A3"
$PN"A3"29;
"VCC"
$PN"A2"48;
%"UNIVERSAL_POWER"
"1","(-2725,-1750)","0","pure_quanta_power","I9";
;
HDL_POWER"P12V_AUX"
CDS_LIB"pure_quanta_power";
"A"15;
END.
